(kicad_pcb
	(version 20260206)
	(generator "pcbnew")
	(generator_version "10.0")
	(general
		(thickness 1.6)
		(legacy_teardrops no)
	)
	(paper "A4")
	(title_block
		(title "dpb — 14545-sa.0730WZS0815.brd")
		(comment 1 "Honey Badger (Wiwynn) / footprints 741-747 of 1066")
	)
	(layers
		(0 "F.Cu" signal "TOP")
		(4 "In1.Cu" signal "L2GND")
		(6 "In2.Cu" signal "L3")
		(8 "In3.Cu" signal "L4VCC")
		(10 "In4.Cu" signal "L5VCC")
		(12 "In5.Cu" signal "L6")
		(14 "In6.Cu" signal "L7GND")
		(2 "B.Cu" signal "BOTTOM")
		(9 "F.Adhes" user "F.Adhesive")
		(11 "B.Adhes" user "B.Adhesive")
		(13 "F.Paste" user "Package Geometry/Pastemask Top")
		(15 "B.Paste" user "Package Geometry/Pastemask Bottom")
		(5 "F.SilkS" user "Ref Des/Silkscreen Top")
		(7 "B.SilkS" user "Ref Des/Silkscreen Bottom")
		(1 "F.Mask" user "Board Geometry/Soldermask Top")
		(3 "B.Mask" user "Board Geometry/Soldermask Bottom")
		(17 "Dwgs.User" user "User.Drawings")
		(19 "Cmts.User" user "User.Comments")
		(21 "Eco1.User" user "User.Eco1")
		(23 "Eco2.User" user "User.Eco2")
		(25 "Edge.Cuts" user "Board Geometry/Outline")
		(27 "Margin" user)
		(31 "F.CrtYd" user "Package Geometry/Place Bound Top")
		(29 "B.CrtYd" user "Package Geometry/Place Bound Bottom")
		(35 "F.Fab" user "Ref Des/Assembly Top")
		(33 "B.Fab" user "Ref Des/Assembly Bottom")
	)
	(footprint ""
		(layer "F.Cu")
		(at 81.661 -96.52 -90)
		(property "Reference" "D24"
			(at 0 0 270)
			(layer "F.SilkS")
			(hide yes)
			(effects
				(font
					(size 1.27 1.27)
				)
			)
		)
		(property "Value" "RB551V30-1-GP"
			(at 0 -6.7818 270)
			(unlocked yes)
			(layer "F.Fab")
			(hide yes)
			(effects
				(font
					(size 1.016 1.016)
					(thickness 0.1524)
				)
			)
		)
		(property "Device Type" "SOD323AKH44"
			(at 0 -8.6868 270)
			(unlocked yes)
			(layer "F.Fab")
			(hide yes)
			(effects
				(font
					(size 1.016 1.016)
					(thickness 0.1524)
				)
			)
		)
		(duplicate_pad_numbers_are_jumpers no)
		(fp_line
			(start -0.889 2.159)
			(end -0.889 -1.9304)
			(stroke
				(width 0.1524)
				(type default)
			)
			(layer "F.SilkS")
		)
		(fp_line
			(start 0.889 2.159)
			(end -0.889 2.159)
			(stroke
				(width 0.1524)
				(type default)
			)
			(layer "F.SilkS")
		)
		(fp_line
			(start 0.762 2.0574)
			(end -0.762 2.0574)
			(stroke
				(width 0.508)
				(type default)
			)
			(layer "F.SilkS")
		)
		(fp_line
			(start -0.889 -1.9304)
			(end 0.889 -1.9304)
			(stroke
				(width 0.1524)
				(type default)
			)
			(layer "F.SilkS")
		)
		(fp_line
			(start 0.889 -1.9304)
			(end 0.889 2.159)
			(stroke
				(width 0.1524)
				(type default)
			)
			(layer "F.SilkS")
		)
		(fp_rect
			(start -1.016 2.3114)
			(end 1.016 -2.0066)
			(stroke
				(width 0)
				(type default)
			)
			(fill no)
			(layer "F.CrtYd")
		)
		(fp_poly
			(pts
				(xy -1.016 -2.0066) (xy 1.016 -2.0066) (xy 1.016 2.3114) (xy -1.016 2.3114)
			)
			(stroke
				(width 0)
				(type default)
			)
			(fill no)
			(layer "F.Fab")
		)
		(pad "A" smd rect
			(at 0 -1.143 270)
			(size 0.5588 1.016)
			(layers "F.Cu" "F.Mask" "F.Paste")
			(net "SW_HDD9_R")
		)
		(pad "K" smd rect
			(at 0 1.143 270)
			(size 0.5588 1.016)
			(layers "F.Cu" "F.Mask" "F.Paste")
			(net "SW_HDD9_N")
		)
	)
	(footprint ""
		(layer "F.Cu")
		(at 45.338746 -40.9067 90)
		(property "Reference" "R228"
			(at 0 0 90)
			(layer "F.SilkS")
			(hide yes)
			(effects
				(font
					(size 1.27 1.27)
				)
			)
		)
		(property "Value" "0R2J-2-GP"
			(at 0.064008 -3.993896 90)
			(unlocked yes)
			(layer "F.Fab")
			(hide yes)
			(effects
				(font
					(size 1.016 1.016)
					(thickness 0.1524)
				)
			)
		)
		(property "Device Type" "R402H16"
			(at 0.064008 -5.517896 90)
			(unlocked yes)
			(layer "F.Fab")
			(hide yes)
			(effects
				(font
					(size 1.016 1.016)
					(thickness 0.1524)
				)
			)
		)
		(duplicate_pad_numbers_are_jumpers no)
		(fp_line
			(start 0.508 -0.9398)
			(end -0.508 -0.9398)
			(stroke
				(width 0.1524)
				(type default)
			)
			(layer "F.SilkS")
		)
		(fp_line
			(start -0.508 -0.9398)
			(end -0.508 0.9398)
			(stroke
				(width 0.1524)
				(type default)
			)
			(layer "F.SilkS")
		)
		(fp_rect
			(start -0.508 0.9398)
			(end 0.508 -0.9398)
			(stroke
				(width 0)
				(type default)
			)
			(fill no)
			(layer "F.CrtYd")
		)
		(fp_rect
			(start -0.508 0.9398)
			(end 0.508 -0.9398)
			(stroke
				(width 0)
				(type default)
			)
			(fill no)
			(layer "F.Fab")
		)
		(pad "1" smd custom
			(at 0 -0.4445 90)
			(size 0.1397 0.1397)
			(layers "F.Cu" "F.Mask" "F.Paste")
			(net "DRV_ACT_NET9")
			(options
				(clearance outline)
				(anchor circle)
			)
			(primitives
				(gr_poly
					(pts
						(arc
							(start -0.1778 -0.2794)
							(mid -0.249642 -0.249642)
							(end -0.2794 -0.1778)
						)
						(arc
							(start -0.2794 0.1778)
							(mid -0.249642 0.249642)
							(end -0.1778 0.2794)
						)
						(arc
							(start 0.1778 0.2794)
							(mid 0.249642 0.249642)
							(end 0.2794 0.1778)
						)
						(arc
							(start 0.2794 -0.1778)
							(mid 0.249642 -0.249642)
							(end 0.1778 -0.2794)
						)
					)
					(width 0)
					(fill yes)
				)
			)
		)
		(pad "2" smd custom
			(at 0 0.4445 90)
			(size 0.1397 0.1397)
			(layers "F.Cu" "F.Mask" "F.Paste")
			(net "DRIVE_ACT_9")
			(options
				(clearance outline)
				(anchor circle)
			)
			(primitives
				(gr_poly
					(pts
						(arc
							(start -0.1778 -0.2794)
							(mid -0.249642 -0.249642)
							(end -0.2794 -0.1778)
						)
						(arc
							(start -0.2794 0.1778)
							(mid -0.249642 0.249642)
							(end -0.1778 0.2794)
						)
						(arc
							(start 0.1778 0.2794)
							(mid 0.249642 0.249642)
							(end 0.2794 0.1778)
						)
						(arc
							(start 0.2794 -0.1778)
							(mid 0.249642 -0.249642)
							(end 0.1778 -0.2794)
						)
					)
					(width 0)
					(fill yes)
				)
			)
		)
	)
	(footprint ""
		(layer "F.Cu")
		(at 80.01 -94.488 180)
		(property "Reference" "R551"
			(at 0 0 180)
			(layer "F.SilkS")
			(hide yes)
			(effects
				(font
					(size 1.27 1.27)
				)
			)
		)
		(property "Value" "200KR2F-L-GP"
			(at 0.064008 -3.993896 180)
			(unlocked yes)
			(layer "F.Fab")
			(hide yes)
			(effects
				(font
					(size 1.016 1.016)
					(thickness 0.1524)
				)
			)
		)
		(property "Device Type" "R402H16"
			(at 0.064008 -5.517896 180)
			(unlocked yes)
			(layer "F.Fab")
			(hide yes)
			(effects
				(font
					(size 1.016 1.016)
					(thickness 0.1524)
				)
			)
		)
		(duplicate_pad_numbers_are_jumpers no)
		(fp_line
			(start 0.508 -0.9398)
			(end -0.508 -0.9398)
			(stroke
				(width 0.1524)
				(type default)
			)
			(layer "F.SilkS")
		)
		(fp_line
			(start -0.508 -0.9398)
			(end -0.508 0.9398)
			(stroke
				(width 0.1524)
				(type default)
			)
			(layer "F.SilkS")
		)
		(fp_rect
			(start -0.508 0.9398)
			(end 0.508 -0.9398)
			(stroke
				(width 0)
				(type default)
			)
			(fill no)
			(layer "F.CrtYd")
		)
		(fp_rect
			(start -0.508 0.9398)
			(end 0.508 -0.9398)
			(stroke
				(width 0)
				(type default)
			)
			(fill no)
			(layer "F.Fab")
		)
		(pad "1" smd custom
			(at 0 -0.4445 180)
			(size 0.1397 0.1397)
			(layers "F.Cu" "F.Mask" "F.Paste")
			(net "SW_HDD9_R")
			(options
				(clearance outline)
				(anchor circle)
			)
			(primitives
				(gr_poly
					(pts
						(arc
							(start -0.1778 -0.2794)
							(mid -0.249642 -0.249642)
							(end -0.2794 -0.1778)
						)
						(arc
							(start -0.2794 0.1778)
							(mid -0.249642 0.249642)
							(end -0.1778 0.2794)
						)
						(arc
							(start 0.1778 0.2794)
							(mid 0.249642 0.249642)
							(end 0.2794 0.1778)
						)
						(arc
							(start 0.2794 -0.1778)
							(mid 0.249642 -0.249642)
							(end 0.1778 -0.2794)
						)
					)
					(width 0)
					(fill yes)
				)
			)
		)
		(pad "2" smd custom
			(at 0 0.4445 180)
			(size 0.1397 0.1397)
			(layers "F.Cu" "F.Mask" "F.Paste")
			(net "SW_HDD9_N")
			(options
				(clearance outline)
				(anchor circle)
			)
			(primitives
				(gr_poly
					(pts
						(arc
							(start -0.1778 -0.2794)
							(mid -0.249642 -0.249642)
							(end -0.2794 -0.1778)
						)
						(arc
							(start -0.2794 0.1778)
							(mid -0.249642 0.249642)
							(end -0.1778 0.2794)
						)
						(arc
							(start 0.1778 0.2794)
							(mid 0.249642 0.249642)
							(end 0.2794 0.1778)
						)
						(arc
							(start 0.2794 -0.1778)
							(mid 0.249642 -0.249642)
							(end 0.1778 -0.2794)
						)
					)
					(width 0)
					(fill yes)
				)
			)
		)
	)
	(footprint ""
		(layer "F.Cu")
		(at 45.338746 -143.2687 90)
		(property "Reference" "R216"
			(at 0 0 90)
			(layer "F.SilkS")
			(hide yes)
			(effects
				(font
					(size 1.27 1.27)
				)
			)
		)
		(property "Value" "0R2J-2-GP"
			(at 0.064008 -3.993896 90)
			(unlocked yes)
			(layer "F.Fab")
			(hide yes)
			(effects
				(font
					(size 1.016 1.016)
					(thickness 0.1524)
				)
			)
		)
		(property "Device Type" "R402H16"
			(at 0.064008 -5.517896 90)
			(unlocked yes)
			(layer "F.Fab")
			(hide yes)
			(effects
				(font
					(size 1.016 1.016)
					(thickness 0.1524)
				)
			)
		)
		(duplicate_pad_numbers_are_jumpers no)
		(fp_line
			(start 0.508 -0.9398)
			(end -0.508 -0.9398)
			(stroke
				(width 0.1524)
				(type default)
			)
			(layer "F.SilkS")
		)
		(fp_line
			(start -0.508 -0.9398)
			(end -0.508 0.9398)
			(stroke
				(width 0.1524)
				(type default)
			)
			(layer "F.SilkS")
		)
		(fp_rect
			(start -0.508 0.9398)
			(end 0.508 -0.9398)
			(stroke
				(width 0)
				(type default)
			)
			(fill no)
			(layer "F.CrtYd")
		)
		(fp_rect
			(start -0.508 0.9398)
			(end 0.508 -0.9398)
			(stroke
				(width 0)
				(type default)
			)
			(fill no)
			(layer "F.Fab")
		)
		(pad "1" smd custom
			(at 0 -0.4445 90)
			(size 0.1397 0.1397)
			(layers "F.Cu" "F.Mask" "F.Paste")
			(net "FLT_NET_HDD8")
			(options
				(clearance outline)
				(anchor circle)
			)
			(primitives
				(gr_poly
					(pts
						(arc
							(start -0.1778 -0.2794)
							(mid -0.249642 -0.249642)
							(end -0.2794 -0.1778)
						)
						(arc
							(start -0.2794 0.1778)
							(mid -0.249642 0.249642)
							(end -0.1778 0.2794)
						)
						(arc
							(start 0.1778 0.2794)
							(mid 0.249642 0.249642)
							(end 0.2794 0.1778)
						)
						(arc
							(start 0.2794 -0.1778)
							(mid 0.249642 -0.249642)
							(end 0.1778 -0.2794)
						)
					)
					(width 0)
					(fill yes)
				)
			)
		)
		(pad "2" smd custom
			(at 0 0.4445 90)
			(size 0.1397 0.1397)
			(layers "F.Cu" "F.Mask" "F.Paste")
			(net "FLT_HDD8_DRIVE")
			(options
				(clearance outline)
				(anchor circle)
			)
			(primitives
				(gr_poly
					(pts
						(arc
							(start -0.1778 -0.2794)
							(mid -0.249642 -0.249642)
							(end -0.2794 -0.1778)
						)
						(arc
							(start -0.2794 0.1778)
							(mid -0.249642 0.249642)
							(end -0.1778 0.2794)
						)
						(arc
							(start 0.1778 0.2794)
							(mid 0.249642 0.249642)
							(end 0.2794 0.1778)
						)
						(arc
							(start 0.2794 -0.1778)
							(mid 0.249642 -0.249642)
							(end 0.1778 -0.2794)
						)
					)
					(width 0)
					(fill yes)
				)
			)
		)
	)
	(footprint ""
		(layer "F.Cu")
		(at 41.0718 -428.1932)
		(property "Reference" "Q67"
			(at 0 0 0)
			(layer "F.SilkS")
			(hide yes)
			(effects
				(font
					(size 1.27 1.27)
				)
			)
		)
		(property "Value" "2N7002-11-GP"
			(at 0.127 -8.9662 0)
			(unlocked yes)
			(layer "F.Fab")
			(hide yes)
			(effects
				(font
					(size 1.016 1.016)
					(thickness 0.1524)
				)
			)
		)
		(property "Device Type" "SOT23DGS2D4H44"
			(at 0.127 -10.4902 0)
			(unlocked yes)
			(layer "F.Fab")
			(hide yes)
			(effects
				(font
					(size 1.016 1.016)
					(thickness 0.1524)
				)
			)
		)
		(duplicate_pad_numbers_are_jumpers no)
		(fp_line
			(start -1.651 -1.778)
			(end -1.651 1.778)
			(stroke
				(width 0.1524)
				(type default)
			)
			(layer "F.SilkS")
		)
		(fp_line
			(start -1.651 1.778)
			(end 1.651 1.778)
			(stroke
				(width 0.1524)
				(type default)
			)
			(layer "F.SilkS")
		)
		(fp_line
			(start 1.651 -1.778)
			(end -1.651 -1.778)
			(stroke
				(width 0.1524)
				(type default)
			)
			(layer "F.SilkS")
		)
		(fp_line
			(start 1.651 1.778)
			(end 1.651 -1.778)
			(stroke
				(width 0.1524)
				(type default)
			)
			(layer "F.SilkS")
		)
		(fp_poly
			(pts
				(xy -1.778 1.8796) (xy -1.778 -1.8796) (xy 1.778 -1.8796) (xy 1.778 1.8796)
			)
			(stroke
				(width 0)
				(type default)
			)
			(fill no)
			(layer "F.CrtYd")
		)
		(fp_poly
			(pts
				(xy -1.778 1.8796) (xy -1.778 -1.8796) (xy 1.778 -1.8796) (xy 1.778 1.8796)
			)
			(stroke
				(width 0)
				(type default)
			)
			(fill no)
			(layer "F.Fab")
		)
		(pad "D" smd custom
			(at 0 -0.9525)
			(size 0.1905 0.1905)
			(layers "F.Cu" "F.Mask" "F.Paste")
			(net "HDD10_LED_G")
			(options
				(clearance outline)
				(anchor circle)
			)
			(primitives
				(gr_poly
					(pts
						(arc
							(start -0.1778 0.5715)
							(mid -0.321484 0.511984)
							(end -0.381 0.3683)
						)
						(arc
							(start -0.381 -0.3683)
							(mid -0.321484 -0.511984)
							(end -0.1778 -0.5715)
						)
						(arc
							(start 0.1778 -0.5715)
							(mid 0.321484 -0.511984)
							(end 0.381 -0.3683)
						)
						(arc
							(start 0.381 0.3683)
							(mid 0.321484 0.511984)
							(end 0.1778 0.5715)
						)
					)
					(width 0)
					(fill yes)
				)
			)
		)
		(pad "G" smd custom
			(at -0.98425 0.9525)
			(size 0.1905 0.1905)
			(layers "F.Cu" "F.Mask" "F.Paste")
			(net "HDD10_LED_B")
			(options
				(clearance outline)
				(anchor circle)
			)
			(primitives
				(gr_poly
					(pts
						(arc
							(start -0.1778 0.5715)
							(mid -0.321484 0.511984)
							(end -0.381 0.3683)
						)
						(arc
							(start -0.381 -0.3683)
							(mid -0.321484 -0.511984)
							(end -0.1778 -0.5715)
						)
						(arc
							(start 0.1778 -0.5715)
							(mid 0.321484 -0.511984)
							(end 0.381 -0.3683)
						)
						(arc
							(start 0.381 0.3683)
							(mid 0.321484 0.511984)
							(end 0.1778 0.5715)
						)
					)
					(width 0)
					(fill yes)
				)
			)
		)
		(pad "S" smd custom
			(at 0.98425 0.9525)
			(size 0.1905 0.1905)
			(layers "F.Cu" "F.Mask" "F.Paste")
			(net "GND")
			(options
				(clearance outline)
				(anchor circle)
			)
			(primitives
				(gr_poly
					(pts
						(arc
							(start -0.1778 0.5715)
							(mid -0.321484 0.511984)
							(end -0.381 0.3683)
						)
						(arc
							(start -0.381 -0.3683)
							(mid -0.321484 -0.511984)
							(end -0.1778 -0.5715)
						)
						(arc
							(start 0.1778 -0.5715)
							(mid 0.321484 -0.511984)
							(end 0.381 -0.3683)
						)
						(arc
							(start 0.381 0.3683)
							(mid 0.321484 0.511984)
							(end 0.1778 0.5715)
						)
					)
					(width 0)
					(fill yes)
				)
			)
		)
	)
	(footprint ""
		(layer "F.Cu")
		(at 26.034746 -35.9537 90)
		(property "Reference" "C327"
			(at 0 0 90)
			(layer "F.SilkS")
			(hide yes)
			(effects
				(font
					(size 1.27 1.27)
				)
			)
		)
		(property "Value" "SCD01U50V2KX-1GP"
			(at 1.1811 -2.7051 90)
			(unlocked yes)
			(layer "F.Fab")
			(hide yes)
			(effects
				(font
					(size 1.016 1.016)
					(thickness 0.1524)
				)
			)
		)
		(property "Device Type" "C402H22"
			(at 1.1811 -4.2291 90)
			(unlocked yes)
			(layer "F.Fab")
			(hide yes)
			(effects
				(font
					(size 1.016 1.016)
					(thickness 0.1524)
				)
			)
		)
		(duplicate_pad_numbers_are_jumpers no)
		(fp_rect
			(start -0.4318 0.9525)
			(end 0.4318 -0.9525)
			(stroke
				(width 0)
				(type default)
			)
			(fill no)
			(layer "F.CrtYd")
		)
		(fp_rect
			(start -0.4318 0.9525)
			(end 0.4318 -0.9525)
			(stroke
				(width 0)
				(type default)
			)
			(fill no)
			(layer "F.Fab")
		)
		(pad "1" smd custom
			(at 0 -0.4445 90)
			(size 0.1524 0.1524)
			(layers "F.Cu" "F.Mask" "F.Paste")
			(net "SAS2X28_DRIVE_RX_P_A14")
			(options
				(clearance outline)
				(anchor circle)
			)
			(primitives
				(gr_poly
					(pts
						(arc
							(start 0.3048 -0.2032)
							(mid 0.275042 -0.275042)
							(end 0.2032 -0.3048)
						)
						(arc
							(start -0.2032 -0.3048)
							(mid -0.275042 -0.275042)
							(end -0.3048 -0.2032)
						)
						(arc
							(start -0.3048 0.2032)
							(mid -0.275042 0.275042)
							(end -0.2032 0.3048)
						)
						(arc
							(start 0.2032 0.3048)
							(mid 0.275042 0.275042)
							(end 0.3048 0.2032)
						)
					)
					(width 0)
					(fill yes)
				)
			)
		)
		(pad "2" smd custom
			(at 0 0.4445 90)
			(size 0.1524 0.1524)
			(layers "F.Cu" "F.Mask" "F.Paste")
			(net "SAS2X28_A_HDD14_RX_+")
			(options
				(clearance outline)
				(anchor circle)
			)
			(primitives
				(gr_poly
					(pts
						(arc
							(start 0.3048 -0.2032)
							(mid 0.275042 -0.275042)
							(end 0.2032 -0.3048)
						)
						(arc
							(start -0.2032 -0.3048)
							(mid -0.275042 -0.275042)
							(end -0.3048 -0.2032)
						)
						(arc
							(start -0.3048 0.2032)
							(mid -0.275042 0.275042)
							(end -0.2032 0.3048)
						)
						(arc
							(start 0.2032 0.3048)
							(mid 0.275042 0.275042)
							(end 0.3048 0.2032)
						)
					)
					(width 0)
					(fill yes)
				)
			)
		)
	)
	(footprint ""
		(layer "F.Cu")
		(at 47.752 -107.315 180)
		(property "Reference" "R576"
			(at 0 0 180)
			(layer "F.SilkS")
			(hide yes)
			(effects
				(font
					(size 1.27 1.27)
				)
			)
		)
		(property "Value" "300KR2F-GP"
			(at 0.064008 -3.993896 180)
			(unlocked yes)
			(layer "F.Fab")
			(hide yes)
			(effects
				(font
					(size 1.016 1.016)
					(thickness 0.1524)
				)
			)
		)
		(property "Device Type" "R402H16"
			(at 0.064008 -5.517896 180)
			(unlocked yes)
			(layer "F.Fab")
			(hide yes)
			(effects
				(font
					(size 1.016 1.016)
					(thickness 0.1524)
				)
			)
		)
		(duplicate_pad_numbers_are_jumpers no)
		(fp_line
			(start 0.508 -0.9398)
			(end -0.508 -0.9398)
			(stroke
				(width 0.1524)
				(type default)
			)
			(layer "F.SilkS")
		)
		(fp_line
			(start -0.508 -0.9398)
			(end -0.508 0.9398)
			(stroke
				(width 0.1524)
				(type default)
			)
			(layer "F.SilkS")
		)
		(fp_rect
			(start -0.508 0.9398)
			(end 0.508 -0.9398)
			(stroke
				(width 0)
				(type default)
			)
			(fill no)
			(layer "F.CrtYd")
		)
		(fp_rect
			(start -0.508 0.9398)
			(end 0.508 -0.9398)
			(stroke
				(width 0)
				(type default)
			)
			(fill no)
			(layer "F.Fab")
		)
		(pad "1" smd custom
			(at 0 -0.4445 180)
			(size 0.1397 0.1397)
			(layers "F.Cu" "F.Mask" "F.Paste")
			(net "SW_HDD13_N")
			(options
				(clearance outline)
				(anchor circle)
			)
			(primitives
				(gr_poly
					(pts
						(arc
							(start -0.1778 -0.2794)
							(mid -0.249642 -0.249642)
							(end -0.2794 -0.1778)
						)
						(arc
							(start -0.2794 0.1778)
							(mid -0.249642 0.249642)
							(end -0.1778 0.2794)
						)
						(arc
							(start 0.1778 0.2794)
							(mid 0.249642 0.249642)
							(end 0.2794 0.1778)
						)
						(arc
							(start 0.2794 -0.1778)
							(mid 0.249642 -0.249642)
							(end 0.1778 -0.2794)
						)
					)
					(width 0)
					(fill yes)
				)
			)
		)
		(pad "2" smd custom
			(at 0 0.4445 180)
			(size 0.1397 0.1397)
			(layers "F.Cu" "F.Mask" "F.Paste")
			(net "P12V")
			(options
				(clearance outline)
				(anchor circle)
			)
			(primitives
				(gr_poly
					(pts
						(arc
							(start -0.1778 -0.2794)
							(mid -0.249642 -0.249642)
							(end -0.2794 -0.1778)
						)
						(arc
							(start -0.2794 0.1778)
							(mid -0.249642 0.249642)
							(end -0.1778 0.2794)
						)
						(arc
							(start 0.1778 0.2794)
							(mid 0.249642 0.249642)
							(end 0.2794 0.1778)
						)
						(arc
							(start 0.2794 -0.1778)
							(mid 0.249642 -0.249642)
							(end 0.1778 -0.2794)
						)
					)
					(width 0)
					(fill yes)
				)
			)
		)
	)
)
